# T6G (Grand Teton) — schematic netlist excerpt (pin names and nets, part order shuffled) for the footprints in the layout excerpt that follows; sources: Cadence DE-HDL packaged netlist, KiCad conversion of 04192023_DAF0TMB3IC0_F0TG_MB_C_brd_V02_OCP.brd

C6630  Q_CAP_DIFFBUS  DIFF BUS_0.22UF 6.3V 20% X6S  pkg C0201  page 319 : \1\ = P5E_CPU1_P0_TX_BUF_C_DN<0> ; \2\ = P5E_CPU1_P0_TX_BUF_DN<0>
PC3272  Q_CAP  1UF 25V 10% X6S  pkg C0402  page 264 : A = HSC_VDD_R_3 ; B = AGND_HSC
PR522  Q_RES  1.5 1% EMPTY  pkg 0402LF  page 212 : A = SW_PVDDCR_CPU0_P1_SW3_RC ; B = GND

(kicad_pcb
	(version 20260206)
	(generator "pcbnew")
	(generator_version "10.0")
	(general
		(thickness 1.6)
		(legacy_teardrops no)
	)
	(paper "A4")
	(title_block
		(title "04192023_DAF0TMB3IC0_F0TG_MB_C_brd_V02_OCP.brd")
		(comment 1 "Grand Teton / footprints 3177-3179 of 8354")
	)
	(layers
		(0 "F.Cu" signal "TOP")
		(4 "In1.Cu" signal "GND")
		(6 "In2.Cu" signal "IN1")
		(8 "In3.Cu" signal "GND1")
		(10 "In4.Cu" signal "IN2")
		(12 "In5.Cu" signal "GND2")
		(14 "In6.Cu" signal "IN3")
		(16 "In7.Cu" signal "GND3")
		(18 "In8.Cu" signal "VCC")
		(20 "In9.Cu" signal "VCC1")
		(22 "In10.Cu" signal "GND4")
		(24 "In11.Cu" signal "IN4")
		(26 "In12.Cu" signal "GND5")
		(28 "In13.Cu" signal "IN5")
		(30 "In14.Cu" signal "GND6")
		(32 "In15.Cu" signal "IN6")
		(34 "In16.Cu" signal "GND7")
		(2 "B.Cu" signal "BOTTOM")
		(9 "F.Adhes" user "F.Adhesive")
		(11 "B.Adhes" user "B.Adhesive")
		(13 "F.Paste" user "Package Geometry/Pastemask Top")
		(15 "B.Paste" user "Package Geometry/Pastemask Bottom")
		(5 "F.SilkS" user "Ref Des/Silkscreen Top")
		(7 "B.SilkS" user "Ref Des/Silkscreen Bottom")
		(1 "F.Mask" user "Board Geometry/Soldermask Top")
		(3 "B.Mask" user "Board Geometry/Soldermask Bottom")
		(17 "Dwgs.User" user "User.Drawings")
		(19 "Cmts.User" user "User.Comments")
		(21 "Eco1.User" user "User.Eco1")
		(23 "Eco2.User" user "User.Eco2")
		(25 "Edge.Cuts" user "Board Geometry/Outline")
		(27 "Margin" user)
		(31 "F.CrtYd" user "Package Geometry/Place Bound Top")
		(29 "B.CrtYd" user "Package Geometry/Place Bound Bottom")
		(35 "F.Fab" user "Ref Des/Assembly Top")
		(33 "B.Fab" user "Ref Des/Assembly Bottom")
	)
	(footprint ""
		(layer "F.Cu")
		(at 102.751128 -184.427368 -90)
		(property "Reference" "PR522"
			(at 0 0 270)
			(layer "F.SilkS")
			(hide yes)
			(effects
				(font
					(size 1.27 1.27)
				)
			)
		)
		(property "Value" ""
			(at 0 0 270)
			(layer "F.Fab")
			(effects
				(font
					(size 1.27 1.27)
				)
			)
		)
		(duplicate_pad_numbers_are_jumpers no)
		(fp_line
			(start -0.7874 0.4064)
			(end -0.7874 -0.4064)
			(stroke
				(width 0.1524)
				(type default)
			)
			(layer "F.SilkS")
		)
		(fp_line
			(start 0.7874 0.4064)
			(end -0.7874 0.4064)
			(stroke
				(width 0.1524)
				(type default)
			)
			(layer "F.SilkS")
		)
		(fp_line
			(start -0.7874 -0.4064)
			(end 0.7874 -0.4064)
			(stroke
				(width 0.1524)
				(type default)
			)
			(layer "F.SilkS")
		)
		(fp_line
			(start 0.7874 -0.4064)
			(end 0.7874 0.4064)
			(stroke
				(width 0.1524)
				(type default)
			)
			(layer "F.SilkS")
		)
		(fp_line
			(start -0.67945 0.3048)
			(end -0.67945 -0.305054)
			(stroke
				(width 0.1)
				(type default)
			)
			(layer "F.Fab")
		)
		(fp_line
			(start -0.12065 0.3048)
			(end -0.67945 0.3048)
			(stroke
				(width 0.1)
				(type default)
			)
			(layer "F.Fab")
		)
		(fp_line
			(start 0.120396 0.3048)
			(end 0.120396 0.2794)
			(stroke
				(width 0.1)
				(type default)
			)
			(layer "F.Fab")
		)
		(fp_line
			(start 0.67945 0.3048)
			(end 0.120396 0.3048)
			(stroke
				(width 0.1)
				(type default)
			)
			(layer "F.Fab")
		)
		(fp_line
			(start -0.12065 0.2794)
			(end -0.12065 0.3048)
			(stroke
				(width 0.1)
				(type default)
			)
			(layer "F.Fab")
		)
		(fp_line
			(start 0.120396 0.2794)
			(end -0.12065 0.2794)
			(stroke
				(width 0.1)
				(type default)
			)
			(layer "F.Fab")
		)
		(fp_line
			(start -0.12065 -0.2794)
			(end 0.12065 -0.2794)
			(stroke
				(width 0.1)
				(type default)
			)
			(layer "F.Fab")
		)
		(fp_line
			(start 0.12065 -0.2794)
			(end 0.12065 -0.3048)
			(stroke
				(width 0.1)
				(type default)
			)
			(layer "F.Fab")
		)
		(fp_line
			(start 0.12065 -0.3048)
			(end 0.67945 -0.3048)
			(stroke
				(width 0.1)
				(type default)
			)
			(layer "F.Fab")
		)
		(fp_line
			(start 0.67945 -0.3048)
			(end 0.67945 0.3048)
			(stroke
				(width 0.1)
				(type default)
			)
			(layer "F.Fab")
		)
		(fp_line
			(start -0.67945 -0.305054)
			(end -0.12065 -0.305054)
			(stroke
				(width 0.1)
				(type default)
			)
			(layer "F.Fab")
		)
		(fp_line
			(start -0.12065 -0.305054)
			(end -0.12065 -0.2794)
			(stroke
				(width 0.1)
				(type default)
			)
			(layer "F.Fab")
		)
		(pad "1" smd circle
			(at -0.40005 0 270)
			(size 0 0)
			(layers "F.Cu" "F.Mask" "F.Paste")
			(net "SW_PVDDCR_CPU0_P1_SW3_RC")
		)
		(pad "2" smd circle
			(at 0.40005 0 270)
			(size 0 0)
			(layers "F.Cu" "F.Mask" "F.Paste")
			(net "GND")
		)
	)
	(footprint ""
		(layer "F.Cu")
		(at 217.1065 -402.191982 90)
		(property "Reference" "PC3272"
			(at 0 0 90)
			(layer "F.SilkS")
			(hide yes)
			(effects
				(font
					(size 1.27 1.27)
				)
			)
		)
		(property "Value" ""
			(at 0 0 90)
			(layer "F.Fab")
			(effects
				(font
					(size 1.27 1.27)
				)
			)
		)
		(duplicate_pad_numbers_are_jumpers no)
		(fp_line
			(start 0.7874 -0.4064)
			(end 0.7874 0.4064)
			(stroke
				(width 0.1524)
				(type default)
			)
			(layer "F.SilkS")
		)
		(fp_line
			(start -0.7874 -0.4064)
			(end 0.7874 -0.4064)
			(stroke
				(width 0.1524)
				(type default)
			)
			(layer "F.SilkS")
		)
		(fp_line
			(start 0.7874 0.4064)
			(end -0.7874 0.4064)
			(stroke
				(width 0.1524)
				(type default)
			)
			(layer "F.SilkS")
		)
		(fp_line
			(start -0.7874 0.4064)
			(end -0.7874 -0.4064)
			(stroke
				(width 0.1524)
				(type default)
			)
			(layer "F.SilkS")
		)
		(fp_line
			(start -0.12065 -0.305054)
			(end -0.12065 -0.2794)
			(stroke
				(width 0.1)
				(type default)
			)
			(layer "F.Fab")
		)
		(fp_line
			(start -0.67945 -0.305054)
			(end -0.12065 -0.305054)
			(stroke
				(width 0.1)
				(type default)
			)
			(layer "F.Fab")
		)
		(fp_line
			(start 0.67945 -0.3048)
			(end 0.67945 0.3048)
			(stroke
				(width 0.1)
				(type default)
			)
			(layer "F.Fab")
		)
		(fp_line
			(start 0.12065 -0.3048)
			(end 0.67945 -0.3048)
			(stroke
				(width 0.1)
				(type default)
			)
			(layer "F.Fab")
		)
		(fp_line
			(start 0.12065 -0.2794)
			(end 0.12065 -0.3048)
			(stroke
				(width 0.1)
				(type default)
			)
			(layer "F.Fab")
		)
		(fp_line
			(start -0.12065 -0.2794)
			(end 0.12065 -0.2794)
			(stroke
				(width 0.1)
				(type default)
			)
			(layer "F.Fab")
		)
		(fp_line
			(start 0.120396 0.2794)
			(end -0.12065 0.2794)
			(stroke
				(width 0.1)
				(type default)
			)
			(layer "F.Fab")
		)
		(fp_line
			(start -0.12065 0.2794)
			(end -0.12065 0.3048)
			(stroke
				(width 0.1)
				(type default)
			)
			(layer "F.Fab")
		)
		(fp_line
			(start 0.67945 0.3048)
			(end 0.120396 0.3048)
			(stroke
				(width 0.1)
				(type default)
			)
			(layer "F.Fab")
		)
		(fp_line
			(start 0.120396 0.3048)
			(end 0.120396 0.2794)
			(stroke
				(width 0.1)
				(type default)
			)
			(layer "F.Fab")
		)
		(fp_line
			(start -0.12065 0.3048)
			(end -0.67945 0.3048)
			(stroke
				(width 0.1)
				(type default)
			)
			(layer "F.Fab")
		)
		(fp_line
			(start -0.67945 0.3048)
			(end -0.67945 -0.305054)
			(stroke
				(width 0.1)
				(type default)
			)
			(layer "F.Fab")
		)
		(pad "1" smd circle
			(at -0.40005 0 90)
			(size 0 0)
			(layers "F.Cu" "F.Mask" "F.Paste")
			(net "HSC_VDD_R_3")
		)
		(pad "2" smd circle
			(at 0.40005 0 90)
			(size 0 0)
			(layers "F.Cu" "F.Mask" "F.Paste")
			(net "AGND_HSC")
		)
	)
	(footprint ""
		(layer "F.Cu")
		(at 47.768764 -408.517344 -90)
		(property "Reference" "C6630"
			(at 0 0 270)
			(layer "F.SilkS")
			(hide yes)
			(effects
				(font
					(size 1.27 1.27)
				)
			)
		)
		(property "Value" ""
			(at 0 0 270)
			(layer "F.Fab")
			(effects
				(font
					(size 1.27 1.27)
				)
			)
		)
		(duplicate_pad_numbers_are_jumpers no)
		(fp_line
			(start -0.299974 0.150114)
			(end -0.299974 -0.150114)
			(stroke
				(width 0.1)
				(type default)
			)
			(layer "F.Fab")
		)
		(fp_line
			(start 0.299974 0.150114)
			(end -0.299974 0.150114)
			(stroke
				(width 0.1)
				(type default)
			)
			(layer "F.Fab")
		)
		(fp_line
			(start -0.299974 -0.150114)
			(end 0.299974 -0.150114)
			(stroke
				(width 0.1)
				(type default)
			)
			(layer "F.Fab")
		)
		(fp_line
			(start 0.299974 -0.150114)
			(end 0.299974 0.150114)
			(stroke
				(width 0.1)
				(type default)
			)
			(layer "F.Fab")
		)
		(pad "1" smd rect
			(at -0.2667 0 270)
			(size 0.3048 0.381)
			(layers "F.Cu" "F.Mask" "F.Paste")
			(net "P5E_CPU1_P0_TX_BUF_C_DN<0>")
		)
		(pad "2" smd rect
			(at 0.2667 0 270)
			(size 0.3048 0.381)
			(layers "F.Cu" "F.Mask" "F.Paste")
			(net "P5E_CPU1_P0_TX_BUF_DN<0>")
		)
	)
)
